FILE_TYPE = CONNECTIVITY;
{Allegro Design Entry HDL 16.6-p007 (v16-6-112F) 10/10/2012}
"PAGE_NUMBER" = 164;
0"NC";
1"P3V3_STBY\g";
2"P3V3_STBY\g";
3"GND\g";
4"GND\g";
5"FM_BOARD_SKU_ID1";
6"FM_BOARD_SKU_ID3";
7"FM_BOARD_SKU_ID0";
8"FM_BOARD_SKU_ID2";
9"FM_BOARD_SKU_ID4";
10"FM_BOARD_REV_ID2";
11"FM_BOARD_REV_ID0";
12"FM_BOARD_REV_ID1";
%"RES"
"1","(-7025,1450)","0","mstr_discrete","I11";
;
CDS_SEC"1"
SEC_TYPE"0402"
BOM_COST"SM_CONTROLLER"
SEC"1"
ROOM"BMC_MISC"
CDS_LOCATION"R1T5"
CDS_LIB"mstr_discrete"
VALUE"2.7K"
WATTAGE"1/16W"
MATERIAL"EMPTY"
PACK_TYPE"0402"
PART_NUMBER"G21796-344"
TOLERANCE"1%"
LOCATION"R1T5";
"B"
$PN"2"10;
"A"
$PN"1"1;
%"P3V3_STBY"
"1","(-7375,1600)","0","mstr_symbols","I12";
;
VOLTAGE"3.3V"
SIZE"1B"
CDS_LIB"mstr_symbols"
BODY_TYPE"PLUMBING"
HDL_POWER"P3V3_STBY";
"G\NAC"1;
%"RES"
"1","(-7025,1250)","0","mstr_discrete","I13";
;
CDS_SEC"1"
BOM_COST"SM_CONTROLLER"
ROOM"BMC_MISC"
SEC"1"
SEC_TYPE"0402"
CDS_LIB"mstr_discrete"
CDS_LOCATION"R1T6"
PACK_TYPE"0402"
MATERIAL"EMPTY"
PART_NUMBER"G21796-344"
WATTAGE"1/16W"
TOLERANCE"1%"
VALUE"2.7K"
LOCATION"R1T6";
"B"
$PN"2"12;
"A"
$PN"1"1;
%"RES"
"1","(-7025,1050)","0","mstr_discrete","I14";
;
CDS_SEC"1"
SEC_TYPE"0402"
BOM_COST"SM_CONTROLLER"
ROOM"BMC_MISC"
CDS_LOCATION"R1T4"
CDS_LIB"mstr_discrete"
SEC"1"
PART_NUMBER"G21796-344"
MATERIAL"CHIP"
PACK_TYPE"0402"
TOLERANCE"1%"
VALUE"2.7K"
WATTAGE"1/16W"
LOCATION"R1T4";
"B"
$PN"2"11;
"A"
$PN"1"1;
%"RES"
"2","(-5475,2150)","0","mstr_discrete","I19";
;
CDS_SEC"1"
CDS_LIB"mstr_discrete"
CDS_LOCATION"R1U18"
SEC_TYPE"0402"
BOM_COST"SM_CONTROLLER"
SEC"1"
ROOM"BMC_MISC"
MATERIAL"CHIP"
PACK_TYPE"0402"
PART_NUMBER"G21796-026"
TOLERANCE"1%"
WATTAGE"1/16W"
VALUE"1.00K"
LOCATION"R1U18";
"A"
$PN"1"7;
"B"
$PN"2"3;
%"RES"
"2","(-5725,2150)","0","mstr_discrete","I20";
;
CDS_SEC"1"
CDS_LIB"mstr_discrete"
CDS_LOCATION"R1U16"
SEC_TYPE"0402"
BOM_COST"SM_CONTROLLER"
SEC"1"
ROOM"BMC_MISC"
WATTAGE"1/16W"
MATERIAL"EMPTY"
PART_NUMBER"G21796-026"
PACK_TYPE"0402"
TOLERANCE"1%"
LOCATION"R1U16"
VALUE"1.00K";
"A"
$PN"1"5;
"B"
$PN"2"3;
%"RES"
"2","(-5975,2150)","0","mstr_discrete","I21";
;
CDS_SEC"1"
CDS_LIB"mstr_discrete"
CDS_LOCATION"R1U17"
BOM_COST"SM_CONTROLLER"
SEC_TYPE"0402"
SEC"1"
ROOM"BMC_MISC"
LOCATION"R1U17"
PART_NUMBER"G21796-026"
PACK_TYPE"0402"
MATERIAL"CHIP"
WATTAGE"1/16W"
VALUE"1.00K"
TOLERANCE"1%";
"A"
$PN"1"8;
"B"
$PN"2"3;
%"RES"
"2","(-6225,2150)","0","mstr_discrete","I22";
;
CDS_SEC"1"
CDS_LIB"mstr_discrete"
CDS_LOCATION"R1U15"
SEC"1"
ROOM"BMC_MISC"
BOM_COST"SM_CONTROLLER"
SEC_TYPE"0402"
VALUE"1.00K"
MATERIAL"EMPTY"
PART_NUMBER"G21796-026"
WATTAGE"1/16W"
PACK_TYPE"0402"
LOCATION"R1U15"
TOLERANCE"1%";
"A"
$PN"1"6;
"B"
$PN"2"3;
%"RES"
"1","(-7025,3075)","0","mstr_discrete","I24";
;
CDS_SEC"1"
SEC_TYPE"0402"
SEC"1"
CDS_LIB"mstr_discrete"
CDS_LOCATION"R1U21"
ROOM"BMC_MISC"
BOM_COST"SM_CONTROLLER"
MATERIAL"CHIP"
LOCATION"R1U21"
VALUE"2.7K"
TOLERANCE"1%"
WATTAGE"1/16W"
PART_NUMBER"G21796-344"
PACK_TYPE"0402";
"B"
$PN"2"6;
"A"
$PN"1"2;
%"RES"
"1","(-7025,2875)","0","mstr_discrete","I25";
;
CDS_SEC"1"
CDS_LOCATION"R1U24"
CDS_LIB"mstr_discrete"
BOM_COST"SM_CONTROLLER"
ROOM"BMC_MISC"
SEC"1"
SEC_TYPE"0402"
MATERIAL"EMPTY"
LOCATION"R1U24"
VALUE"2.7K"
TOLERANCE"1%"
WATTAGE"1/16W"
PART_NUMBER"G21796-344"
PACK_TYPE"0402";
"B"
$PN"2"8;
"A"
$PN"1"2;
%"P3V3_STBY"
"1","(-7375,3450)","0","mstr_symbols","I26";
;
VOLTAGE"3.3V"
CDS_LIB"mstr_symbols"
SIZE"1B"
BODY_TYPE"PLUMBING"
HDL_POWER"P3V3_STBY";
"G\NAC"2;
%"RES"
"1","(-7025,2675)","0","mstr_discrete","I27";
;
CDS_SEC"1"
CDS_LIB"mstr_discrete"
CDS_LOCATION"R1U22"
ROOM"BMC_MISC"
BOM_COST"SM_CONTROLLER"
SEC_TYPE"0402"
SEC"1"
MATERIAL"CHIP"
LOCATION"R1U22"
VALUE"2.7K"
TOLERANCE"1%"
WATTAGE"1/16W"
PART_NUMBER"G21796-344"
PACK_TYPE"0402";
"B"
$PN"2"5;
"A"
$PN"1"2;
%"RES"
"1","(-7025,2475)","0","mstr_discrete","I28";
;
CDS_SEC"1"
CDS_LIB"mstr_discrete"
CDS_LOCATION"R1U23"
ROOM"BMC_MISC"
SEC"1"
SEC_TYPE"0402"
BOM_COST"SM_CONTROLLER"
MATERIAL"EMPTY"
LOCATION"R1U23"
VALUE"2.7K"
TOLERANCE"1%"
WATTAGE"1/16W"
PART_NUMBER"G21796-344"
PACK_TYPE"0402";
"B"
$PN"2"7;
"A"
$PN"1"2;
%"RES"
"1","(-7025,3275)","0","mstr_discrete","I29";
;
ROOM"BMC_MISC"
BOM_COST"SM_CONTROLLER"
CDS_SEC"1"
$SEC"1"
CDS_LIB"mstr_discrete"
CDS_LOCATION"R2N17"
VALUE"2.7K"
LOCATION"R2N17"
PACK_TYPE"0402"
MATERIAL"EMPTY"
PART_NUMBER"G21796-344"
WATTAGE"1/16W"
TOLERANCE"1%";
"B"
$PN"2"9;
"A"
$PN"1"2;
%"GND"
"1","(-6475,1850)","0","mstr_symbols","I31";
;
SIZE"1B"
HDL_POWER"GND"
VOLTAGE"0.0V"
BODY_TYPE"PLUMBING"
CDS_LIB"mstr_symbols";
"A\NAC"3;
%"RES"
"2","(-6475,2150)","0","mstr_discrete","I32";
;
ROOM"BMC_MISC"
BOM_COST"SM_CONTROLLER"
CDS_SEC"1"
$SEC"1"
CDS_LOCATION"R2N18"
CDS_LIB"mstr_discrete"
TOLERANCE"1%"
LOCATION"R2N18"
VALUE"1.00K"
WATTAGE"1/16W"
MATERIAL"CHIP"
PART_NUMBER"G21796-026"
PACK_TYPE"0402";
"A"
$PN"1"9;
"B"
$PN"2"3;
%"RES"
"2","(-5975,775)","0","mstr_discrete","I5";
;
CDS_SEC"1"
SEC"1"
BOM_COST"SM_CONTROLLER"
SEC_TYPE"0402"
ROOM"BMC_MISC"
CDS_LOCATION"R1T10"
CDS_LIB"mstr_discrete"
WATTAGE"1/16W"
PACK_TYPE"0402"
VALUE"1.00K"
PART_NUMBER"G21796-026"
LOCATION"R1T10"
MATERIAL"EMPTY"
TOLERANCE"1%";
"A"
$PN"1"11;
"B"
$PN"2"4;
%"RES"
"2","(-6225,775)","0","mstr_discrete","I6";
;
CDS_SEC"1"
SEC"1"
SEC_TYPE"0402"
BOM_COST"SM_CONTROLLER"
CDS_LIB"mstr_discrete"
CDS_LOCATION"R1T12"
ROOM"BMC_MISC"
LOCATION"R1T12"
WATTAGE"1/16W"
MATERIAL"CHIP"
PACK_TYPE"0402"
VALUE"1.00K"
PART_NUMBER"G21796-026"
TOLERANCE"1%";
"A"
$PN"1"12;
"B"
$PN"2"4;
%"RES"
"2","(-6475,775)","0","mstr_discrete","I7";
;
CDS_SEC"1"
SEC"1"
BOM_COST"SM_CONTROLLER"
SEC_TYPE"0402"
ROOM"BMC_MISC"
CDS_LOCATION"R1T11"
CDS_LIB"mstr_discrete"
VALUE"1.00K"
WATTAGE"1/16W"
MATERIAL"CHIP"
PACK_TYPE"0402"
TOLERANCE"1%"
PART_NUMBER"G21796-026"
LOCATION"R1T11";
"A"
$PN"1"10;
"B"
$PN"2"4;
%"GND"
"1","(-6475,475)","0","mstr_symbols","I9";
;
HDL_POWER"GND"
CDS_LIB"mstr_symbols"
BODY_TYPE"PLUMBING"
SIZE"1B"
VOLTAGE"0.0V";
"A\NAC"4;
END.
